# T6G (Grand Teton) — schematic netlist excerpt (pin names and nets, part order shuffled) for the footprints in the layout excerpt that follows; sources: Cadence DE-HDL packaged netlist, KiCad conversion of 04192023_DAF0TMB3IC0_F0TG_MB_C_brd_V02_OCP.brd

R6127  Q_RES  1K 1% CHIP  pkg 0402LF  page 84 : A = FM_BOARD_SKU_ID2 ; B = GND
C2364  Q_CAP  22UF 4V 20% X6S  pkg C0402  page 73 : A = PVDDCR_CPU1_P1 ; B = GND

(kicad_pcb
	(version 20260206)
	(generator "pcbnew")
	(generator_version "10.0")
	(general
		(thickness 1.6)
		(legacy_teardrops no)
	)
	(paper "A4")
	(title_block
		(title "04192023_DAF0TMB3IC0_F0TG_MB_C_brd_V02_OCP.brd")
		(comment 1 "Grand Teton / footprints 5647-5648 of 8354")
	)
	(layers
		(0 "F.Cu" signal "TOP")
		(4 "In1.Cu" signal "GND")
		(6 "In2.Cu" signal "IN1")
		(8 "In3.Cu" signal "GND1")
		(10 "In4.Cu" signal "IN2")
		(12 "In5.Cu" signal "GND2")
		(14 "In6.Cu" signal "IN3")
		(16 "In7.Cu" signal "GND3")
		(18 "In8.Cu" signal "VCC")
		(20 "In9.Cu" signal "VCC1")
		(22 "In10.Cu" signal "GND4")
		(24 "In11.Cu" signal "IN4")
		(26 "In12.Cu" signal "GND5")
		(28 "In13.Cu" signal "IN5")
		(30 "In14.Cu" signal "GND6")
		(32 "In15.Cu" signal "IN6")
		(34 "In16.Cu" signal "GND7")
		(2 "B.Cu" signal "BOTTOM")
		(9 "F.Adhes" user "F.Adhesive")
		(11 "B.Adhes" user "B.Adhesive")
		(13 "F.Paste" user "Package Geometry/Pastemask Top")
		(15 "B.Paste" user "Package Geometry/Pastemask Bottom")
		(5 "F.SilkS" user "Ref Des/Silkscreen Top")
		(7 "B.SilkS" user "Ref Des/Silkscreen Bottom")
		(1 "F.Mask" user "Board Geometry/Soldermask Top")
		(3 "B.Mask" user "Board Geometry/Soldermask Bottom")
		(17 "Dwgs.User" user "User.Drawings")
		(19 "Cmts.User" user "User.Comments")
		(21 "Eco1.User" user "User.Eco1")
		(23 "Eco2.User" user "User.Eco2")
		(25 "Edge.Cuts" user "Board Geometry/Outline")
		(27 "Margin" user)
		(31 "F.CrtYd" user "Package Geometry/Place Bound Top")
		(29 "B.CrtYd" user "Package Geometry/Place Bound Bottom")
		(35 "F.Fab" user "Ref Des/Assembly Top")
		(33 "B.Fab" user "Ref Des/Assembly Bottom")
	)
	(footprint ""
		(layer "B.Cu")
		(at 123.865386 -268.418564)
		(property "Reference" "C2364"
			(at 0 0 0)
			(layer "B.SilkS")
			(hide yes)
			(effects
				(font
					(size 1.27 1.27)
				)
				(justify mirror)
			)
		)
		(property "Value" ""
			(at 0 0 0)
			(layer "B.Fab")
			(effects
				(font
					(size 1.27 1.27)
				)
				(justify mirror)
			)
		)
		(duplicate_pad_numbers_are_jumpers no)
		(fp_line
			(start -0.7874 -0.4064)
			(end -0.7874 0.4064)
			(stroke
				(width 0.1524)
				(type default)
			)
			(layer "B.SilkS")
		)
		(fp_line
			(start -0.7874 0.4064)
			(end 0.7874 0.4064)
			(stroke
				(width 0.1524)
				(type default)
			)
			(layer "B.SilkS")
		)
		(fp_line
			(start 0.7874 -0.4064)
			(end -0.7874 -0.4064)
			(stroke
				(width 0.1524)
				(type default)
			)
			(layer "B.SilkS")
		)
		(fp_line
			(start 0.7874 0.4064)
			(end 0.7874 -0.4064)
			(stroke
				(width 0.1524)
				(type default)
			)
			(layer "B.SilkS")
		)
		(fp_line
			(start -0.67945 -0.3048)
			(end -0.67945 0.3048)
			(stroke
				(width 0.1)
				(type default)
			)
			(layer "B.Fab")
		)
		(fp_line
			(start -0.67945 0.3048)
			(end -0.120396 0.3048)
			(stroke
				(width 0.1)
				(type default)
			)
			(layer "B.Fab")
		)
		(fp_line
			(start -0.12065 -0.3048)
			(end -0.67945 -0.3048)
			(stroke
				(width 0.1)
				(type default)
			)
			(layer "B.Fab")
		)
		(fp_line
			(start -0.12065 -0.2794)
			(end -0.12065 -0.3048)
			(stroke
				(width 0.1)
				(type default)
			)
			(layer "B.Fab")
		)
		(fp_line
			(start -0.120396 0.2794)
			(end 0.12065 0.2794)
			(stroke
				(width 0.1)
				(type default)
			)
			(layer "B.Fab")
		)
		(fp_line
			(start -0.120396 0.3048)
			(end -0.120396 0.2794)
			(stroke
				(width 0.1)
				(type default)
			)
			(layer "B.Fab")
		)
		(fp_line
			(start 0.12065 -0.305054)
			(end 0.12065 -0.2794)
			(stroke
				(width 0.1)
				(type default)
			)
			(layer "B.Fab")
		)
		(fp_line
			(start 0.12065 -0.2794)
			(end -0.12065 -0.2794)
			(stroke
				(width 0.1)
				(type default)
			)
			(layer "B.Fab")
		)
		(fp_line
			(start 0.12065 0.2794)
			(end 0.12065 0.3048)
			(stroke
				(width 0.1)
				(type default)
			)
			(layer "B.Fab")
		)
		(fp_line
			(start 0.12065 0.3048)
			(end 0.67945 0.3048)
			(stroke
				(width 0.1)
				(type default)
			)
			(layer "B.Fab")
		)
		(fp_line
			(start 0.67945 -0.305054)
			(end 0.12065 -0.305054)
			(stroke
				(width 0.1)
				(type default)
			)
			(layer "B.Fab")
		)
		(fp_line
			(start 0.67945 0.3048)
			(end 0.67945 -0.305054)
			(stroke
				(width 0.1)
				(type default)
			)
			(layer "B.Fab")
		)
		(pad "1" smd circle
			(at 0.40005 0 180)
			(size 0 0)
			(layers "B.Cu" "B.Mask" "B.Paste")
			(net "PVDDCR_CPU1_P1")
		)
		(pad "2" smd circle
			(at -0.40005 0 180)
			(size 0 0)
			(layers "B.Cu" "B.Mask" "B.Paste")
			(net "GND")
		)
	)
	(footprint ""
		(layer "B.Cu")
		(at 404.568152 -354.439728 -90)
		(property "Reference" "R6127"
			(at 0 0 90)
			(layer "B.SilkS")
			(hide yes)
			(effects
				(font
					(size 1.27 1.27)
				)
				(justify mirror)
			)
		)
		(property "Value" ""
			(at 0 0 90)
			(layer "B.Fab")
			(effects
				(font
					(size 1.27 1.27)
				)
				(justify mirror)
			)
		)
		(duplicate_pad_numbers_are_jumpers no)
		(fp_line
			(start -0.7874 0.4064)
			(end 0.7874 0.4064)
			(stroke
				(width 0.1524)
				(type default)
			)
			(layer "B.SilkS")
		)
		(fp_line
			(start 0.7874 0.4064)
			(end 0.7874 -0.4064)
			(stroke
				(width 0.1524)
				(type default)
			)
			(layer "B.SilkS")
		)
		(fp_line
			(start -0.7874 -0.4064)
			(end -0.7874 0.4064)
			(stroke
				(width 0.1524)
				(type default)
			)
			(layer "B.SilkS")
		)
		(fp_line
			(start 0.7874 -0.4064)
			(end -0.7874 -0.4064)
			(stroke
				(width 0.1524)
				(type default)
			)
			(layer "B.SilkS")
		)
		(fp_line
			(start -0.67945 0.3048)
			(end -0.120396 0.3048)
			(stroke
				(width 0.1)
				(type default)
			)
			(layer "B.Fab")
		)
		(fp_line
			(start -0.120396 0.3048)
			(end -0.120396 0.2794)
			(stroke
				(width 0.1)
				(type default)
			)
			(layer "B.Fab")
		)
		(fp_line
			(start 0.12065 0.3048)
			(end 0.67945 0.3048)
			(stroke
				(width 0.1)
				(type default)
			)
			(layer "B.Fab")
		)
		(fp_line
			(start 0.67945 0.3048)
			(end 0.67945 -0.305054)
			(stroke
				(width 0.1)
				(type default)
			)
			(layer "B.Fab")
		)
		(fp_line
			(start -0.120396 0.2794)
			(end 0.12065 0.2794)
			(stroke
				(width 0.1)
				(type default)
			)
			(layer "B.Fab")
		)
		(fp_line
			(start 0.12065 0.2794)
			(end 0.12065 0.3048)
			(stroke
				(width 0.1)
				(type default)
			)
			(layer "B.Fab")
		)
		(fp_line
			(start -0.12065 -0.2794)
			(end -0.12065 -0.3048)
			(stroke
				(width 0.1)
				(type default)
			)
			(layer "B.Fab")
		)
		(fp_line
			(start 0.12065 -0.2794)
			(end -0.12065 -0.2794)
			(stroke
				(width 0.1)
				(type default)
			)
			(layer "B.Fab")
		)
		(fp_line
			(start -0.67945 -0.3048)
			(end -0.67945 0.3048)
			(stroke
				(width 0.1)
				(type default)
			)
			(layer "B.Fab")
		)
		(fp_line
			(start -0.12065 -0.3048)
			(end -0.67945 -0.3048)
			(stroke
				(width 0.1)
				(type default)
			)
			(layer "B.Fab")
		)
		(fp_line
			(start 0.12065 -0.305054)
			(end 0.12065 -0.2794)
			(stroke
				(width 0.1)
				(type default)
			)
			(layer "B.Fab")
		)
		(fp_line
			(start 0.67945 -0.305054)
			(end 0.12065 -0.305054)
			(stroke
				(width 0.1)
				(type default)
			)
			(layer "B.Fab")
		)
		(pad "1" smd circle
			(at 0.40005 0 90)
			(size 0 0)
			(layers "B.Cu" "B.Mask" "B.Paste")
			(net "FM_BOARD_SKU_ID2")
		)
		(pad "2" smd circle
			(at -0.40005 0 90)
			(size 0 0)
			(layers "B.Cu" "B.Mask" "B.Paste")
			(net "GND")
		)
	)
)
